FILE_TYPE = CONNECTIVITY;
{Allegro Design Entry HDL 17.2-2016 S081 (4005846) 1/11/2022}
"PAGE_NUMBER" = 106;
0"NC";
1"P3V3_AUX\g";
2"P12V_S3_AUX_CPU1_NVDIMM\g";
3"P12V_S3_AUX_CPU1_NVDIMM\g";
4"P3V3_AUX\g";
5"GND\g";
6"GND\g";
7"GND\g";
8"GND\g";
9"GND\g";
10"M_E_CPU1_SA_DQ<31:0>";
11"M_E_CPU1_SA_CB<7:0>";
12"M_E_CPU1_SB_CB<7:0>";
13"M_E_CPU1_SA_CA<6:0>";
14"M_E_CPU1_SB_CA<6:0>";
15"M_E_CPU1_SB_DQ<31:0>";
16"M_E_CPU1_SB_DQS_DP<9:0>";
17"M_E_CPU1_SA_DQS_DP<9:0>";
18"M_E_CPU1_SB_DQS_DN<9:0>";
19"M_E_CPU1_SA_DQS_DN<9:0>";
20"I3C_SPD_DDREFGH_CPU1_LVC1_SCL_R1";
21"I3C_SPD_DDREFGH_CPU1_LVC1_SDA";
22"PD_CHE_CPU1_DIMM1_SAA";
23"M_E_CPU1_ALERT_N";
24"RST_M_EF_CPU1_FPGA_N";
25"I3C_SPD_DDREFGH_CPU1_LVC1_SCL";
26"M_E_CPU1_SB_DQS_DP<5>";
27"M_E_CPU1_SB_DQS_DN<5>";
28"M_E_CPU1_SA_DQS_DN<9>";
29"M_E_CPU1_SA_DQS_DN<8>";
30"M_E_CPU1_SA_DQS_DN<7>";
31"M_E_CPU1_SA_DQS_DN<6>";
32"M_E_CPU1_SA_DQS_DN<5>";
33"M_E_CPU1_SA_DQS_DN<4>";
34"M_E_CPU1_SA_DQS_DN<3>";
35"M_E_CPU1_SA_DQS_DN<2>";
36"M_E_CPU1_SA_DQS_DN<1>";
37"M_E_CPU1_SA_DQS_DN<0>";
38"M_E_CPU1_SB_DQS_DN<9>";
39"M_E_CPU1_SB_DQS_DN<8>";
40"M_E_CPU1_SB_DQS_DN<7>";
41"M_E_CPU1_SB_DQS_DN<6>";
42"M_E_CPU1_SB_DQS_DN<4>";
43"M_E_CPU1_SB_DQS_DN<3>";
44"M_E_CPU1_SB_DQS_DN<1>";
45"M_E_CPU1_SB_DQS_DN<2>";
46"M_E_CPU1_SB_DQS_DN<0>";
47"M_E_CPU1_SA_DQS_DP<9>";
48"M_E_CPU1_SA_DQS_DP<8>";
49"M_E_CPU1_SA_DQS_DP<7>";
50"M_E_CPU1_SA_DQS_DP<6>";
51"M_E_CPU1_SA_DQS_DP<5>";
52"M_E_CPU1_SA_DQS_DP<4>";
53"M_E_CPU1_SA_DQS_DP<3>";
54"M_E_CPU1_SA_DQS_DP<2>";
55"M_E_CPU1_SA_DQS_DP<1>";
56"M_E_CPU1_SA_DQS_DP<0>";
57"M_E_CPU1_SB_DQS_DP<9>";
58"M_E_CPU1_SB_DQS_DP<8>";
59"M_E_CPU1_SB_DQS_DP<7>";
60"M_E_CPU1_SB_DQS_DP<6>";
61"M_E_CPU1_SB_DQS_DP<4>";
62"M_E_CPU1_SB_DQS_DP<3>";
63"M_E_CPU1_SB_DQS_DP<2>";
64"M_E_CPU1_SB_DQS_DP<1>";
65"M_E_CPU1_SB_DQS_DP<0>";
66"TP_CHE_CPU1_DIMM1_FRU_6";
67"TP_CHE_CPU1_DIMM1_FRU_5";
68"PWRGD_CHE_CPU1_DIMM1";
69"TP_CHE_CPU1_DIMM1_FRU_2";
70"TP_CHE_CPU1_DIMM1_FRU_3";
71"M_E_CPU1_SB_DQ<30>";
72"M_E_CPU1_SB_CA<0>";
73"M_E_CPU1_SA_PAR";
74"M_E_CPU1_SB_PAR";
75"M_E_CPU1_SB_DQ<26>";
76"M_E_CPU1_SB_DQ<25>";
77"M_E_CPU1_SB_DQ<24>";
78"M_E_CPU1_SB_DQ<19>";
79"M_E_CPU1_SB_CB<2>";
80"M_E_CPU1_CLK_DN<0>";
81"M_E_CPU1_SA_DQ<6>";
82"M_E_CPU1_SB_DQ<29>";
83"TP_CHE_CPU1_DIMM1_FRU_0";
84"TP_CHE_CPU1_DIMM1_FRU_1";
85"TP_CHE_CPU1_DIMM1_FRU_4";
86"M_E_CPU1_SB_RSP<0>";
87"M_E_CPU1_SA_RSP<0>";
88"M_E_CPU1_SB_DQ<0>";
89"M_E_CPU1_SB_DQ<1>";
90"M_E_CPU1_SB_DQ<2>";
91"M_E_CPU1_SB_DQ<3>";
92"M_E_CPU1_SB_DQ<4>";
93"M_E_CPU1_SB_DQ<5>";
94"M_E_CPU1_SB_DQ<6>";
95"M_E_CPU1_SB_DQ<7>";
96"M_E_CPU1_SB_DQ<8>";
97"M_E_CPU1_SB_DQ<9>";
98"M_E_CPU1_SB_DQ<10>";
99"M_E_CPU1_SB_DQ<11>";
100"M_E_CPU1_SB_DQ<12>";
101"M_E_CPU1_SB_DQ<13>";
102"M_E_CPU1_SB_DQ<14>";
103"M_E_CPU1_SB_DQ<15>";
104"M_E_CPU1_SB_DQ<16>";
105"M_E_CPU1_SB_DQ<17>";
106"M_E_CPU1_SB_DQ<18>";
107"M_E_CPU1_SB_DQ<20>";
108"M_E_CPU1_SB_DQ<21>";
109"M_E_CPU1_SB_DQ<22>";
110"M_E_CPU1_SB_DQ<23>";
111"M_E_CPU1_SB_DQ<27>";
112"M_E_CPU1_SB_DQ<28>";
113"M_E_CPU1_SB_DQ<31>";
114"M_E_CPU1_SA_DQ<0>";
115"M_E_CPU1_SA_DQ<1>";
116"M_E_CPU1_SA_DQ<2>";
117"M_E_CPU1_SA_DQ<3>";
118"M_E_CPU1_SA_DQ<4>";
119"M_E_CPU1_SA_DQ<5>";
120"M_E_CPU1_SA_DQ<7>";
121"M_E_CPU1_SA_DQ<8>";
122"M_E_CPU1_SA_DQ<9>";
123"M_E_CPU1_SA_DQ<10>";
124"M_E_CPU1_SA_DQ<11>";
125"M_E_CPU1_SA_DQ<12>";
126"M_E_CPU1_SA_DQ<13>";
127"M_E_CPU1_SA_DQ<14>";
128"M_E_CPU1_SA_DQ<15>";
129"M_E_CPU1_SA_DQ<16>";
130"M_E_CPU1_SA_DQ<17>";
131"M_E_CPU1_SA_DQ<18>";
132"M_E_CPU1_SA_DQ<19>";
133"M_E_CPU1_SA_DQ<20>";
134"M_E_CPU1_SA_DQ<21>";
135"M_E_CPU1_SA_DQ<22>";
136"M_E_CPU1_SA_DQ<23>";
137"M_E_CPU1_SA_DQ<24>";
138"M_E_CPU1_SA_DQ<25>";
139"M_E_CPU1_SA_DQ<26>";
140"M_E_CPU1_SA_DQ<27>";
141"M_E_CPU1_SA_DQ<28>";
142"M_E_CPU1_SA_DQ<29>";
143"M_E_CPU1_SA_DQ<30>";
144"M_E_CPU1_SB_CS_N<1>";
145"M_E_CPU1_SA_CS_N<1>";
146"M_E_CPU1_SB_CS_N<0>";
147"M_E_CPU1_SA_CS_N<0>";
148"M_E_CPU1_CLK_DP<0>";
149"M_E_CPU1_SB_CB<0>";
150"M_E_CPU1_SB_CB<1>";
151"M_E_CPU1_SB_CB<3>";
152"M_E_CPU1_SB_CB<4>";
153"M_E_CPU1_SB_CB<5>";
154"M_E_CPU1_SB_CB<6>";
155"M_E_CPU1_SA_CB<0>";
156"M_E_CPU1_SA_CB<2>";
157"M_E_CPU1_SA_CB<3>";
158"M_E_CPU1_SA_CB<5>";
159"M_E_CPU1_SA_CB<6>";
160"M_E_CPU1_SB_CA<6>";
161"M_E_CPU1_SA_CA<6>";
162"M_E_CPU1_SB_CA<5>";
163"M_E_CPU1_SA_CA<5>";
164"M_E_CPU1_SB_CA<4>";
165"M_E_CPU1_SA_CA<4>";
166"M_E_CPU1_SB_CA<3>";
167"M_E_CPU1_SA_CA<3>";
168"M_E_CPU1_SB_CA<2>";
169"M_E_CPU1_SA_CA<2>";
170"M_E_CPU1_SB_CA<1>";
171"M_E_CPU1_SA_CA<1>";
172"M_E_CPU1_SA_CA<0>";
173"M_E_CPU1_SB_CB<7>";
174"M_E_CPU1_SA_CB<1>";
175"M_E_CPU1_SA_CB<4>";
176"M_E_CPU1_SA_CB<7>";
177"M_E_CPU1_SA_DQ<31>";
178"PD_CHE_CPU1_DIMM1_SAA";
%"UNIVERSAL_GND"
"1","(-2525,-400)","0","logical_power","I1";
;
HDL_POWER"GND"
CDS_LIB"logical_power";
"A"5;
%"TAP"
"1","(-1100,3025)","0","standard","I100";
;
CDS_LIB"standard"
BODY_TYPE"PLUMBING"
HDL_TAP"TRUE";
"B \NAC \NWC"10;
"S \NAC"
BN"12"125;
%"TAP"
"1","(-1100,3125)","0","standard","I101";
;
CDS_LIB"standard"
BODY_TYPE"PLUMBING"
HDL_TAP"TRUE";
"B \NAC \NWC"10;
"S \NAC"
BN"14"127;
%"TAP"
"1","(-1100,3075)","0","standard","I102";
;
CDS_LIB"standard"
BODY_TYPE"PLUMBING"
HDL_TAP"TRUE";
"B \NAC \NWC"10;
"S \NAC"
BN"13"126;
%"TAP"
"1","(-1100,3275)","0","standard","I103";
;
CDS_LIB"standard"
BODY_TYPE"PLUMBING"
HDL_TAP"TRUE";
"B \NAC \NWC"10;
"S \NAC"
BN"17"130;
%"TAP"
"1","(-1100,3175)","0","standard","I104";
;
CDS_LIB"standard"
BODY_TYPE"PLUMBING"
HDL_TAP"TRUE";
"B \NAC \NWC"10;
"S \NAC"
BN"15"128;
%"TAP"
"1","(-1100,3225)","0","standard","I105";
;
CDS_LIB"standard"
BODY_TYPE"PLUMBING"
HDL_TAP"TRUE";
"B \NAC \NWC"10;
"S \NAC"
BN"16"129;
%"TAP"
"1","(-1100,3375)","0","standard","I106";
;
CDS_LIB"standard"
BODY_TYPE"PLUMBING"
HDL_TAP"TRUE";
"B \NAC \NWC"10;
"S \NAC"
BN"19"132;
%"TAP"
"1","(-1100,3325)","0","standard","I107";
;
CDS_LIB"standard"
BODY_TYPE"PLUMBING"
HDL_TAP"TRUE";
"B \NAC \NWC"10;
"S \NAC"
BN"18"131;
%"TAP"
"1","(-1100,3525)","0","standard","I108";
;
CDS_LIB"standard"
BODY_TYPE"PLUMBING"
HDL_TAP"TRUE";
"B \NAC \NWC"10;
"S \NAC"
BN"22"135;
%"TAP"
"1","(-1100,3475)","0","standard","I109";
;
CDS_LIB"standard"
BODY_TYPE"PLUMBING"
HDL_TAP"TRUE";
"B \NAC \NWC"10;
"S \NAC"
BN"21"134;
%"TAP"
"1","(-1100,3425)","0","standard","I110";
;
CDS_LIB"standard"
BODY_TYPE"PLUMBING"
HDL_TAP"TRUE";
"B \NAC \NWC"10;
"S \NAC"
BN"20"133;
%"TAP"
"1","(-1100,3625)","0","standard","I111";
;
CDS_LIB"standard"
BODY_TYPE"PLUMBING"
HDL_TAP"TRUE";
"B \NAC \NWC"10;
"S \NAC"
BN"24"137;
%"TAP"
"1","(-1100,3575)","0","standard","I112";
;
CDS_LIB"standard"
BODY_TYPE"PLUMBING"
HDL_TAP"TRUE";
"B \NAC \NWC"10;
"S \NAC"
BN"23"136;
%"TAP"
"1","(-1100,3775)","0","standard","I113";
;
CDS_LIB"standard"
BODY_TYPE"PLUMBING"
HDL_TAP"TRUE";
"B \NAC \NWC"10;
"S \NAC"
BN"27"140;
%"TAP"
"1","(-1100,3725)","0","standard","I114";
;
CDS_LIB"standard"
BODY_TYPE"PLUMBING"
HDL_TAP"TRUE";
"B \NAC \NWC"10;
"S \NAC"
BN"26"139;
%"TAP"
"1","(-1100,3675)","0","standard","I115";
;
CDS_LIB"standard"
BODY_TYPE"PLUMBING"
HDL_TAP"TRUE";
"B \NAC \NWC"10;
"S \NAC"
BN"25"138;
%"TAP"
"1","(-1100,3875)","0","standard","I116";
;
CDS_LIB"standard"
BODY_TYPE"PLUMBING"
HDL_TAP"TRUE";
"B \NAC \NWC"10;
"S \NAC"
BN"29"142;
%"TAP"
"1","(-1100,3825)","0","standard","I117";
;
CDS_LIB"standard"
BODY_TYPE"PLUMBING"
HDL_TAP"TRUE";
"B \NAC \NWC"10;
"S \NAC"
BN"28"141;
%"TAP"
"1","(-1100,3925)","0","standard","I118";
;
CDS_LIB"standard"
BODY_TYPE"PLUMBING"
HDL_TAP"TRUE";
"B \NAC \NWC"10;
"S \NAC"
BN"30"143;
%"TAP"
"1","(-1100,3975)","0","standard","I119";
;
CDS_LIB"standard"
BODY_TYPE"PLUMBING"
HDL_TAP"TRUE";
"B \NAC \NWC"10;
"S \NAC"
BN"31"177;
%"VCC_CORE"
"1","(-3575,1850)","0","logical_power","I12";
;
HDL_POWER"P3V3_AUX"
CDS_LIB"logical_power";
"A"4;
%"UNIVERSAL_GND"
"1","(625,-275)","0","logical_power","I120";
;
HDL_POWER"GND"
CDS_LIB"logical_power";
"A"6;
%"UNIVERSAL_GND"
"1","(2250,-275)","0","logical_power","I121";
;
HDL_POWER"GND"
CDS_LIB"logical_power";
"A"7;
%"Q_CAP"
"1","(625,100)","0","pure_quanta","I122";
;
PART_NUMBER"CH5221MEB00"
PACK_TYPE"C0402"
MATERIAL"X6S"
VOLTAGE"6.3V"
VALUE"2.2UF"
TOLERANCE"20%"
$LOCATION"C93"
CDS_LIB"pure_quanta"
$LOCATION"C93"
CDS_LOCATION"C93"
$SEC"1"
CDS_SEC"1";
"B"
$PN"2"6;
"A"
$PN"1"1;
%"VCC_CORE"
"1","(625,425)","0","logical_power","I123";
;
HDL_POWER"P3V3_AUX"
CDS_LIB"logical_power";
"A"1;
%"Q_CAP"
"1","(1625,100)","0","pure_quanta","I127";
;
PART_NUMBER"CH6103KEA00"
PACK_TYPE"C0805"
TOLERANCE"10%"
VALUE"10UF"
VOLTAGE"16V"
MATERIAL"X6S"
$LOCATION"C94"
CDS_LIB"pure_quanta"
$LOCATION"C94"
CDS_LOCATION"C94"
$SEC"1"
CDS_SEC"1";
"B"
$PN"2"7;
"A"
$PN"1"2;
%"VCC_CORE"
"1","(1625,425)","0","logical_power","I128";
;
HDL_POWER"P12V_S3_AUX_CPU1_NVDIMM"
CDS_LIB"logical_power";
"A"2;
%"TAP"
"1","(1825,1975)","0","standard","I129";
;
CDS_LIB"standard"
BODY_TYPE"PLUMBING"
HDL_TAP"TRUE";
"B \NAC \NWC"18;
"S \NAC"
BN"0"46;
%"Q_CAP"
"1","(2250,100)","0","pure_quanta","I130";
;
PART_NUMBER"CH6103KEA00"
VALUE"10UF"
TOLERANCE"10%"
VOLTAGE"16V"
PACK_TYPE"C0805"
MATERIAL"X6S"
$LOCATION"C95"
CDS_LIB"pure_quanta"
$LOCATION"C95"
CDS_LOCATION"C95"
$SEC"1"
CDS_SEC"1";
"B"
$PN"2"7;
"A"
$PN"1"2;
%"TAP"
"1","(1650,2025)","0","standard","I131";
;
CDS_LIB"standard"
BODY_TYPE"PLUMBING"
HDL_TAP"TRUE";
"B \NAC \NWC"16;
"S \NAC"
BN"0"65;
%"TAP"
"1","(1650,2225)","0","standard","I132";
;
CDS_LIB"standard"
BODY_TYPE"PLUMBING"
HDL_TAP"TRUE";
"B \NAC \NWC"16;
"S \NAC"
BN"2"63;
%"TAP"
"1","(1650,2125)","0","standard","I133";
;
CDS_LIB"standard"
BODY_TYPE"PLUMBING"
HDL_TAP"TRUE";
"B \NAC \NWC"16;
"S \NAC"
BN"1"64;
%"TAP"
"1","(1650,2425)","0","standard","I134";
;
CDS_LIB"standard"
BODY_TYPE"PLUMBING"
HDL_TAP"TRUE";
"B \NAC \NWC"16;
"S \NAC"
BN"4"61;
%"TAP"
"1","(1650,2325)","0","standard","I135";
;
CDS_LIB"standard"
BODY_TYPE"PLUMBING"
HDL_TAP"TRUE";
"B \NAC \NWC"16;
"S \NAC"
BN"3"62;
%"TAP"
"1","(1825,2075)","0","standard","I136";
;
CDS_LIB"standard"
BODY_TYPE"PLUMBING"
HDL_TAP"TRUE";
"B \NAC \NWC"18;
"S \NAC"
BN"1"44;
%"TAP"
"1","(1825,2175)","0","standard","I137";
;
CDS_LIB"standard"
BODY_TYPE"PLUMBING"
HDL_TAP"TRUE";
"B \NAC \NWC"18;
"S \NAC"
BN"2"45;
%"TAP"
"1","(1825,2275)","0","standard","I138";
;
CDS_LIB"standard"
BODY_TYPE"PLUMBING"
HDL_TAP"TRUE";
"B \NAC \NWC"18;
"S \NAC"
BN"3"43;
%"TAP"
"1","(1825,2375)","0","standard","I139";
;
CDS_LIB"standard"
BODY_TYPE"PLUMBING"
HDL_TAP"TRUE";
"B \NAC \NWC"18;
"S \NAC"
BN"4"42;
%"TAP"
"1","(1825,2475)","0","standard","I140";
;
CDS_LIB"standard"
BODY_TYPE"PLUMBING"
HDL_TAP"TRUE";
"B \NAC \NWC"18;
"S \NAC"
BN"5"27;
%"TAP"
"1","(1650,2525)","0","standard","I141";
;
CDS_LIB"standard"
BODY_TYPE"PLUMBING"
HDL_TAP"TRUE";
"B \NAC \NWC"16;
"S \NAC"
BN"5"26;
%"TAP"
"1","(1650,2725)","0","standard","I142";
;
CDS_LIB"standard"
BODY_TYPE"PLUMBING"
HDL_TAP"TRUE";
"B \NAC \NWC"16;
"S \NAC"
BN"7"59;
%"TAP"
"1","(1650,2625)","0","standard","I143";
;
CDS_LIB"standard"
BODY_TYPE"PLUMBING"
HDL_TAP"TRUE";
"B \NAC \NWC"16;
"S \NAC"
BN"6"60;
%"TAP"
"1","(1650,2925)","0","standard","I144";
;
CDS_LIB"standard"
BODY_TYPE"PLUMBING"
HDL_TAP"TRUE";
"B \NAC \NWC"16;
"S \NAC"
BN"9"57;
%"TAP"
"1","(1650,2825)","0","standard","I145";
;
CDS_LIB"standard"
BODY_TYPE"PLUMBING"
HDL_TAP"TRUE";
"B \NAC \NWC"16;
"S \NAC"
BN"8"58;
%"TAP"
"1","(1825,2575)","0","standard","I146";
;
CDS_LIB"standard"
BODY_TYPE"PLUMBING"
HDL_TAP"TRUE";
"B \NAC \NWC"18;
"S \NAC"
BN"6"41;
%"TAP"
"1","(1825,2675)","0","standard","I147";
;
CDS_LIB"standard"
BODY_TYPE"PLUMBING"
HDL_TAP"TRUE";
"B \NAC \NWC"18;
"S \NAC"
BN"7"40;
%"TAP"
"1","(1825,2875)","0","standard","I148";
;
CDS_LIB"standard"
BODY_TYPE"PLUMBING"
HDL_TAP"TRUE";
"B \NAC \NWC"18;
"S \NAC"
BN"9"38;
%"TAP"
"1","(1825,2775)","0","standard","I149";
;
CDS_LIB"standard"
BODY_TYPE"PLUMBING"
HDL_TAP"TRUE";
"B \NAC \NWC"18;
"S \NAC"
BN"8"39;
%"TAP"
"1","(1650,3075)","0","standard","I150";
;
CDS_LIB"standard"
BODY_TYPE"PLUMBING"
HDL_TAP"TRUE";
"B \NAC \NWC"17;
"S \NAC"
BN"0"56;
%"TAP"
"1","(1650,3175)","0","standard","I151";
;
CDS_LIB"standard"
BODY_TYPE"PLUMBING"
HDL_TAP"TRUE";
"B \NAC \NWC"17;
"S \NAC"
BN"1"55;
%"TAP"
"1","(1650,3275)","0","standard","I152";
;
CDS_LIB"standard"
BODY_TYPE"PLUMBING"
HDL_TAP"TRUE";
"B \NAC \NWC"17;
"S \NAC"
BN"2"54;
%"TAP"
"1","(1650,3475)","0","standard","I153";
;
CDS_LIB"standard"
BODY_TYPE"PLUMBING"
HDL_TAP"TRUE";
"B \NAC \NWC"17;
"S \NAC"
BN"4"52;
%"TAP"
"1","(1650,3375)","0","standard","I154";
;
CDS_LIB"standard"
BODY_TYPE"PLUMBING"
HDL_TAP"TRUE";
"B \NAC \NWC"17;
"S \NAC"
BN"3"53;
%"TAP"
"1","(1825,3025)","0","standard","I155";
;
CDS_LIB"standard"
BODY_TYPE"PLUMBING"
HDL_TAP"TRUE";
"B \NAC \NWC"19;
"S \NAC"
BN"0"37;
%"TAP"
"1","(1825,3125)","0","standard","I156";
;
CDS_LIB"standard"
BODY_TYPE"PLUMBING"
HDL_TAP"TRUE";
"B \NAC \NWC"19;
"S \NAC"
BN"1"36;
%"TAP"
"1","(1825,3225)","0","standard","I157";
;
CDS_LIB"standard"
BODY_TYPE"PLUMBING"
HDL_TAP"TRUE";
"B \NAC \NWC"19;
"S \NAC"
BN"2"35;
%"TAP"
"1","(1825,3325)","0","standard","I158";
;
CDS_LIB"standard"
BODY_TYPE"PLUMBING"
HDL_TAP"TRUE";
"B \NAC \NWC"19;
"S \NAC"
BN"3"34;
%"TAP"
"1","(1825,3525)","0","standard","I159";
;
CDS_LIB"standard"
BODY_TYPE"PLUMBING"
HDL_TAP"TRUE";
"B \NAC \NWC"19;
"S \NAC"
BN"5"32;
%"TAP"
"1","(1825,3425)","0","standard","I160";
;
CDS_LIB"standard"
BODY_TYPE"PLUMBING"
HDL_TAP"TRUE";
"B \NAC \NWC"19;
"S \NAC"
BN"4"33;
%"TAP"
"1","(1650,3575)","0","standard","I161";
;
CDS_LIB"standard"
BODY_TYPE"PLUMBING"
HDL_TAP"TRUE";
"B \NAC \NWC"17;
"S \NAC"
BN"5"51;
%"TAP"
"1","(1650,3675)","0","standard","I162";
;
CDS_LIB"standard"
BODY_TYPE"PLUMBING"
HDL_TAP"TRUE";
"B \NAC \NWC"17;
"S \NAC"
BN"6"50;
%"TAP"
"1","(1650,3775)","0","standard","I163";
;
CDS_LIB"standard"
BODY_TYPE"PLUMBING"
HDL_TAP"TRUE";
"B \NAC \NWC"17;
"S \NAC"
BN"7"49;
%"TAP"
"1","(1650,3975)","0","standard","I164";
;
CDS_LIB"standard"
BODY_TYPE"PLUMBING"
HDL_TAP"TRUE";
"B \NAC \NWC"17;
"S \NAC"
BN"9"47;
%"TAP"
"1","(1650,3875)","0","standard","I165";
;
CDS_LIB"standard"
BODY_TYPE"PLUMBING"
HDL_TAP"TRUE";
"B \NAC \NWC"17;
"S \NAC"
BN"8"48;
%"TAP"
"1","(1825,3625)","0","standard","I166";
;
CDS_LIB"standard"
BODY_TYPE"PLUMBING"
HDL_TAP"TRUE";
"B \NAC \NWC"19;
"S \NAC"
BN"6"31;
%"TAP"
"1","(1825,3725)","0","standard","I167";
;
CDS_LIB"standard"
BODY_TYPE"PLUMBING"
HDL_TAP"TRUE";
"B \NAC \NWC"19;
"S \NAC"
BN"7"30;
%"TAP"
"1","(1825,3825)","0","standard","I168";
;
CDS_LIB"standard"
BODY_TYPE"PLUMBING"
HDL_TAP"TRUE";
"B \NAC \NWC"19;
"S \NAC"
BN"8"29;
%"TAP"
"1","(1825,3925)","0","standard","I169";
;
CDS_LIB"standard"
BODY_TYPE"PLUMBING"
HDL_TAP"TRUE";
"B \NAC \NWC"19;
"S \NAC"
BN"9"28;
%"UNIVERSAL_GND"
"1","(3325,275)","0","logical_power","I174";
;
HDL_POWER"GND"
CDS_LIB"logical_power";
"A"8;
%"UNIVERSAL_GND"
"1","(5025,275)","0","logical_power","I176";
;
HDL_POWER"GND"
CDS_LIB"logical_power";
"A"9;
%"VCC_CORE"
"1","(3325,4525)","0","logical_power","I177";
;
HDL_POWER"P12V_S3_AUX_CPU1_NVDIMM"
CDS_LIB"logical_power";
"A"3;
%"SCONN288_ADR50017P130CC"
"3","(4175,2350)","0","pure_quanta","I178";
;
PART_NUMBER"DFHST8FS461"
PART_TYPE"SMLF"
VALUE"SCONN288_ADR50017-P130CC"
MATERIAL"IO"
$LOCATION"J25"
NEEDS_NO_SIZE"TRUE"
CDS_LMAN_SYM_OUTLINE"-450,1775,450,-1775"
CDS_LIB"pure_quanta"
CDS_LOCATION"J25"
$SEC"3"
CDS_SEC"3";
"G3"
$PN"G3"9;
"G2"
$PN"G2"9;
"G1"
$PN"G1"9;
"VSS62"
$PN"141"9;
"VSS61"
$PN"139"9;
"VSS60"
$PN"136"9;
"VSS58"
$PN"132"9;
"VSS104"
$PN"240"8;
"VSS102"
$PN"235"8;
"VSS100"
$PN"230"8;
"VIN_BULK2"
$PN"146"3;
"VIN_BULK1"
$PN"145"3;
"VIN_BULK0"
$PN"1"3;
"VSS126"
$PN"288"8;
"VSS125"
$PN"286"8;
"VSS124"
$PN"284"8;
"VSS123"
$PN"281"8;
"VSS122"
$PN"279"8;
"VSS121"
$PN"277"8;
"VSS120"
$PN"275"8;
"VSS119"
$PN"273"8;
"VSS118"
$PN"270"8;
"VSS117"
$PN"268"8;
"VSS116"
$PN"266"8;
"VSS115"
$PN"264"8;
"VSS114"
$PN"262"8;
"VSS113"
$PN"259"8;
"VSS112"
$PN"257"8;
"VSS111"
$PN"255"8;
"VSS110"
$PN"253"8;
"VSS109"
$PN"251"8;
"VSS108"
$PN"248"8;
"VSS107"
$PN"246"8;
"VSS106"
$PN"244"8;
"VSS105"
$PN"242"8;
"VSS103"
$PN"237"8;
"VSS101"
$PN"233"8;
"VSS99"
$PN"228"8;
"VSS98"
$PN"226"8;
"VSS97"
$PN"224"8;
"VSS96"
$PN"222"8;
"VSS95"
$PN"219"8;
"VSS94"
$PN"216"8;
"VSS93"
$PN"214"8;
"VSS92"
$PN"212"8;
"VSS91"
$PN"210"8;
"VSS90"
$PN"208"8;
"VSS89"
$PN"206"8;
"VSS88"
$PN"204"8;
"VSS87"
$PN"202"8;
"VSS86"
$PN"199"8;
"VSS85"
$PN"197"8;
"VSS84"
$PN"195"8;
"VSS83"
$PN"193"8;
"VSS82"
$PN"191"8;
"VSS81"
$PN"188"8;
"VSS80"
$PN"186"8;
"VSS79"
$PN"184"8;
"VSS78"
$PN"182"8;
"VSS77"
$PN"180"8;
"VSS76"
$PN"177"8;
"VSS75"
$PN"175"8;
"VSS74"
$PN"173"8;
"VSS73"
$PN"171"8;
"VSS72"
$PN"169"8;
"VSS71"
$PN"166"8;
"VSS70"
$PN"164"8;
"VSS69"
$PN"162"8;
"VSS68"
$PN"160"8;
"VSS67"
$PN"158"8;
"VSS66"
$PN"155"8;
"VSS65"
$PN"153"8;
"VSS64"
$PN"151"8;
"VSS63"
$PN"143"9;
"VSS59"
$PN"134"9;
"VSS57"
$PN"130"9;
"VSS56"
$PN"128"9;
"VSS55"
$PN"125"9;
"VSS54"
$PN"123"9;
"VSS53"
$PN"121"9;
"VSS52"
$PN"119"9;
"VSS51"
$PN"117"9;
"VSS50"
$PN"114"9;
"VSS49"
$PN"112"9;
"VSS48"
$PN"110"9;
"VSS47"
$PN"108"9;
"VSS46"
$PN"106"9;
"VSS45"
$PN"103"9;
"VSS44"
$PN"101"9;
"VSS43"
$PN"99"9;
"VSS42"
$PN"97"9;
"VSS41"
$PN"95"9;
"VSS40"
$PN"92"9;
"VSS39"
$PN"90"9;
"VSS38"
$PN"88"9;
"VSS37"
$PN"85"9;
"VSS36"
$PN"83"9;
"VSS35"
$PN"81"9;
"VSS34"
$PN"79"9;
"VSS33"
$PN"77"9;
"VSS32"
$PN"75"9;
"VSS31"
$PN"73"9;
"VSS30"
$PN"71"9;
"VSS29"
$PN"69"9;
"VSS28"
$PN"67"9;
"VSS27"
$PN"65"9;
"VSS26"
$PN"63"9;
"VSS25"
$PN"61"9;
"VSS24"
$PN"59"9;
"VSS23"
$PN"57"9;
"VSS22"
$PN"54"9;
"VSS21"
$PN"52"9;
"VSS20"
$PN"50"9;
"VSS19"
$PN"48"9;
"VSS18"
$PN"46"9;
"VSS17"
$PN"43"9;
"VSS16"
$PN"41"9;
"VSS15"
$PN"39"9;
"VSS14"
$PN"37"9;
"VSS13"
$PN"35"9;
"VSS12"
$PN"32"9;
"VSS11"
$PN"30"9;
"VSS10"
$PN"28"9;
"VSS9"
$PN"26"9;
"VSS8"
$PN"24"9;
"VSS7"
$PN"21"9;
"VSS6"
$PN"19"9;
"VSS5"
$PN"17"9;
"VSS4"
$PN"15"9;
"VSS3"
$PN"13"9;
"VSS2"
$PN"10"9;
"VSS1"
$PN"8"9;
"VSS0"
$PN"6"9;
%"SCONN288_ADR50017P130CC"
"1","(-1925,2250)","0","pure_quanta","I180";
;
PART_NUMBER"DFHST8FS461"
MATERIAL"IO"
VALUE"SCONN288_ADR50017-P130CC"
PART_TYPE"SMLF"
$LOCATION"J25"
NEEDS_NO_SIZE"TRUE"
CDS_LMAN_SYM_OUTLINE"-450,1875,450,-1875"
CDS_LIB"pure_quanta"
CDS_LOCATION"J25"
$SEC"1"
CDS_SEC"1";
"DQ31_A"
$PN"194"177;
"CB7_A"
$PN"205"176;
"CB4_A"
$PN"58"175;
"CB1_A"
$PN"53"174;
"CB7_B"
$PN"236"173;
"ALERT_N \B"
$PN"62"23;
"CA0_A"
$PN"66"172;
"CA0_B"
$PN"76"72;
"CA1_A"
$PN"211"171;
"CA1_B"
$PN"221"170;
"CA2_A"
$PN"68"169;
"CA2_B"
$PN"78"168;
"CA3_A"
$PN"213"167;
"CA3_B"
$PN"223"166;
"CA4_A"
$PN"70"165;
"CA4_B"
$PN"80"164;
"CA5_A"
$PN"215"163;
"CA5_B"
$PN"225"162;
"CA6_A"
$PN"72"161;
"CA6_B"
$PN"82"160;
"CB6_A"
$PN"203"159;
"CB5_A"
$PN"60"158;
"CB3_A"
$PN"198"157;
"CB2_A"
$PN"196"156;
"CB0_A"
$PN"51"155;
"CB6_B"
$PN"234"154;
"CB5_B"
$PN"91"153;
"CB4_B"
$PN"89"152;
"CB3_B"
$PN"243"151;
"CB2_B"
$PN"241"79;
"CB1_B"
$PN"98"150;
"CB0_B"
$PN"96"149;
"CK_C \B"
$PN"218"80;
"CK_T"
$PN"217"148;
"CS0_A_N"
$PN"64"147;
"CS0_B_N"
$PN"84"146;
"CS1_A_N"
$PN"209"145;
"CS1_B_N"
$PN"229"144;
"DQ30_A"
$PN"192"143;
"DQ29_A"
$PN"49"142;
"DQ28_A"
$PN"47"141;
"DQ27_A"
$PN"187"140;
"DQ26_A"
$PN"185"139;
"DQ25_A"
$PN"42"138;
"DQ24_A"
$PN"40"137;
"DQ23_A"
$PN"183"136;
"DQ22_A"
$PN"181"135;
"DQ21_A"
$PN"38"134;
"DQ20_A"
$PN"36"133;
"DQ19_A"
$PN"176"132;
"DQ18_A"
$PN"174"131;
"DQ17_A"
$PN"31"130;
"DQ16_A"
$PN"29"129;
"DQ15_A"
$PN"172"128;
"DQ14_A"
$PN"170"127;
"DQ13_A"
$PN"27"126;
"DQ12_A"
$PN"25"125;
"DQ11_A"
$PN"165"124;
"DQ10_A"
$PN"163"123;
"DQ9_A"
$PN"20"122;
"DQ8_A"
$PN"18"121;
"DQ7_A"
$PN"161"120;
"DQ6_A"
$PN"159"81;
"DQ5_A"
$PN"16"119;
"DQ4_A"
$PN"14"118;
"DQ3_A"
$PN"154"117;
"DQ2_A"
$PN"152"116;
"DQ1_A"
$PN"9"115;
"DQ0_A"
$PN"7"114;
"DQ31_B"
$PN"287"113;
"DQ30_B"
$PN"285"71;
"DQ29_B"
$PN"142"82;
"DQ28_B"
$PN"140"112;
"DQ27_B"
$PN"280"111;
"DQ26_B"
$PN"278"75;
"DQ25_B"
$PN"135"76;
"DQ24_B"
$PN"133"77;
"DQ23_B"
$PN"276"110;
"DQ22_B"
$PN"274"109;
"DQ21_B"
$PN"131"108;
"DQ20_B"
$PN"129"107;
"DQ19_B"
$PN"269"78;
"DQ18_B"
$PN"267"106;
"DQ17_B"
$PN"124"105;
"DQ16_B"
$PN"122"104;
"DQ15_B"
$PN"265"103;
"DQ14_B"
$PN"263"102;
"DQ13_B"
$PN"120"101;
"DQ12_B"
$PN"118"100;
"DQ11_B"
$PN"258"99;
"DQ10_B"
$PN"256"98;
"DQ9_B"
$PN"113"97;
"DQ8_B"
$PN"111"96;
"DQ7_B"
$PN"254"95;
"DQ6_B"
$PN"252"94;
"DQ5_B"
$PN"109"93;
"DQ4_B"
$PN"107"92;
"DQ3_B"
$PN"247"91;
"DQ2_B"
$PN"245"90;
"DQ1_B"
$PN"102"89;
"DQ0_B"
$PN"100"88;
"HSA"
$PN"148"22;
"HSCL"
$PN"4"20;
"HSDA"
$PN"5"21;
"LBD||RSP_A_N"
$PN"86"87;
"LBS||RSP_B_N"
$PN"87"86;
"PAR_A"
$PN"74"73;
"PAR_B"
$PN"227"74;
"PWR_GOOD||FAIL_N"
$PN"147"68;
"RESET_N \B"
$PN"207"24;
"RFU6"
$PN"232"66;
"RFU5"
$PN"231"67;
"RFU4"
$PN"220"85;
"RFU3"
$PN"150"70;
"RFU2"
$PN"149"69;
"RFU1"
$PN"144"84;
"RFU0"
$PN"2"83;
"VIN_MGMT"
$PN"3"4;
%"SCONN288_ADR50017P130CC"
"2","(750,2975)","0","pure_quanta","I181";
;
PART_NUMBER"DFHST8FS461"
MATERIAL"IO"
PART_TYPE"SMLF"
VALUE"SCONN288_ADR50017-P130CC"
LOCATION"J25"
NEEDS_NO_SIZE"TRUE"
CDS_LMAN_SYM_OUTLINE"-600,1150,600,-1150"
CDS_LIB"pure_quanta"
$SEC"2"
CDS_SEC"2";
"DQS7_A_C||TDQS7_A_C \B"
$PN"178"30;
"DQS6_A_T||TDQS6_A_T"
$PN"168"50;
"DQS8_B_T||TDQS8_B_T"
$PN"283"58;
"DQS8_B_C||TDQS8_B_C \B"
$PN"282"39;
"DQS7_B_T||TDQS7_B_T"
$PN"272"59;
"DQS0_A_C \B"
$PN"12"37;
"DQS0_A_T"
$PN"11"56;
"DQS0_B_C \B"
$PN"105"46;
"DQS0_B_T"
$PN"104"65;
"DQS1_A_C \B"
$PN"23"36;
"DQS1_A_T"
$PN"22"55;
"DQS1_B_C \B"
$PN"116"44;
"DQS1_B_T"
$PN"115"64;
"DQS2_A_C \B"
$PN"34"35;
"DQS2_A_T"
$PN"33"54;
"DQS2_B_C \B"
$PN"127"45;
"DQS2_B_T"
$PN"126"63;
"DQS3_A_C \B"
$PN"45"34;
"DQS3_A_T"
$PN"44"53;
"DQS3_B_C \B"
$PN"138"43;
"DQS3_B_T"
$PN"137"62;
"DQS4_A_C \B"
$PN"56"33;
"DQS4_A_T"
$PN"55"52;
"DQS4_B_C \B"
$PN"238"42;
"DQS4_B_T"
$PN"239"61;
"DQS5_A_C||TDQS5_A_C||DQS5_A_T||TDQS5_A_T \B"
$PN"156"32;
"DQS5_A_T||TDQS5_A_T"
$PN"157"51;
"DQS5_B_C||TDQS5_B_C \B"
$PN"249"27;
"DQS5_B_T||TDQS5_B_T"
$PN"250"26;
"DQS6_A_C||TDQS6_A_C||DQS6_A_T||TDQS6_A_T \B"
$PN"167"31;
"DQS6_B_C||TDQS6_B_C \B"
$PN"260"41;
"DQS6_B_T||TDQS6_B_T"
$PN"261"60;
"DQS7_A_T||TDQS7_A_T"
$PN"179"49;
"DQS7_B_C||TDQS7_B_C \B"
$PN"271"40;
"DQS8_A_C||TDQS8_A_C \B"
$PN"189"29;
"DQS8_A_T||TDQS8_A_T"
$PN"190"48;
"DQS9_A_C||TDQS9_A_C \B"
$PN"200"28;
"DQS9_A_T||TDQS9_A_T"
$PN"201"47;
"DQS9_B_C||TDQS9_B_C \B"
$PN"94"38;
"DQS9_B_T||TDQS9_B_T||DBI4_B_N"
$PN"93"57;
%"Q_RES"
"1","(-3725,1275)","0","pure_quanta","I183";
;
PART_NUMBER"CS04992FB07"
VALUE"49.9"
MATERIAL"CHIP"
$LOCATION"R3899"
CDS_LIB"pure_quanta"
PACK_TYPE"0402LF"
TOLERANCE"1%"
WATTAGE"1/16W"
CDS_LOCATION"R3899"
$SEC"1"
CDS_SEC"1";
"B"
$PN"2"25;
"A"
$PN"1"20;
%"Q_RES"
"2","(-2525,-175)","0","pure_quanta","I2";
;
PART_NUMBER"CS31002FB08"
VALUE"10K"
TOLERANCE"1%"
WATTAGE"1/16W"
MATERIAL"CHIP"
PACK_TYPE"0402LF"
$LOCATION"R79"
CDS_LIB"pure_quanta"
$LOCATION"R79"
CDS_LOCATION"R79"
$SEC"1"
CDS_SEC"1";
"A"
$PN"1"178;
"B"
$PN"2"5;
%"TAP"
"1","(-2750,1925)","2","standard","I26";
;
CDS_LIB"standard"
BODY_TYPE"PLUMBING"
HDL_TAP"TRUE";
"B \NAC \NWC"12;
"S \NAC"
BN"3"151;
%"TAP"
"1","(-2750,1875)","2","standard","I27";
;
CDS_LIB"standard"
BODY_TYPE"PLUMBING"
HDL_TAP"TRUE";
"B \NAC \NWC"12;
"S \NAC"
BN"2"79;
%"TAP"
"1","(-2750,1775)","2","standard","I28";
;
CDS_LIB"standard"
BODY_TYPE"PLUMBING"
HDL_TAP"TRUE";
"B \NAC \NWC"12;
"S \NAC"
BN"0"149;
%"TAP"
"1","(-2750,1825)","2","standard","I29";
;
CDS_LIB"standard"
BODY_TYPE"PLUMBING"
HDL_TAP"TRUE";
"B \NAC \NWC"12;
"S \NAC"
BN"1"150;
%"TAP"
"1","(-2750,1975)","2","standard","I30";
;
CDS_LIB"standard"
BODY_TYPE"PLUMBING"
HDL_TAP"TRUE";
"B \NAC \NWC"12;
"S \NAC"
BN"4"152;
%"TAP"
"1","(-1100,825)","0","standard","I31";
;
CDS_LIB"standard"
BODY_TYPE"PLUMBING"
HDL_TAP"TRUE";
"B \NAC \NWC"15;
"S \NAC"
BN"1"89;
%"TAP"
"1","(-1100,775)","0","standard","I32";
;
CDS_LIB"standard"
BODY_TYPE"PLUMBING"
HDL_TAP"TRUE";
"B \NAC \NWC"15;
"S \NAC"
BN"0"88;
%"TAP"
"1","(-1100,875)","0","standard","I33";
;
CDS_LIB"standard"
BODY_TYPE"PLUMBING"
HDL_TAP"TRUE";
"B \NAC \NWC"15;
"S \NAC"
BN"2"90;
%"TAP"
"1","(-1100,925)","0","standard","I34";
;
CDS_LIB"standard"
BODY_TYPE"PLUMBING"
HDL_TAP"TRUE";
"B \NAC \NWC"15;
"S \NAC"
BN"3"91;
%"TAP"
"1","(-1100,975)","0","standard","I35";
;
CDS_LIB"standard"
BODY_TYPE"PLUMBING"
HDL_TAP"TRUE";
"B \NAC \NWC"15;
"S \NAC"
BN"4"92;
%"TAP"
"1","(-1100,1025)","0","standard","I36";
;
CDS_LIB"standard"
BODY_TYPE"PLUMBING"
HDL_TAP"TRUE";
"B \NAC \NWC"15;
"S \NAC"
BN"5"93;
%"TAP"
"1","(-1100,1075)","0","standard","I37";
;
CDS_LIB"standard"
BODY_TYPE"PLUMBING"
HDL_TAP"TRUE";
"B \NAC \NWC"15;
"S \NAC"
BN"6"94;
%"TAP"
"1","(-1100,1225)","0","standard","I38";
;
CDS_LIB"standard"
BODY_TYPE"PLUMBING"
HDL_TAP"TRUE";
"B \NAC \NWC"15;
"S \NAC"
BN"9"97;
%"TAP"
"1","(-1100,1175)","0","standard","I39";
;
CDS_LIB"standard"
BODY_TYPE"PLUMBING"
HDL_TAP"TRUE";
"B \NAC \NWC"15;
"S \NAC"
BN"8"96;
%"TAP"
"1","(-1100,1125)","0","standard","I40";
;
CDS_LIB"standard"
BODY_TYPE"PLUMBING"
HDL_TAP"TRUE";
"B \NAC \NWC"15;
"S \NAC"
BN"7"95;
%"TAP"
"1","(-1100,1325)","0","standard","I41";
;
CDS_LIB"standard"
BODY_TYPE"PLUMBING"
HDL_TAP"TRUE";
"B \NAC \NWC"15;
"S \NAC"
BN"11"99;
%"TAP"
"1","(-1100,1275)","0","standard","I42";
;
CDS_LIB"standard"
BODY_TYPE"PLUMBING"
HDL_TAP"TRUE";
"B \NAC \NWC"15;
"S \NAC"
BN"10"98;
%"TAP"
"1","(-1100,1475)","0","standard","I43";
;
CDS_LIB"standard"
BODY_TYPE"PLUMBING"
HDL_TAP"TRUE";
"B \NAC \NWC"15;
"S \NAC"
BN"14"102;
%"TAP"
"1","(-1100,1425)","0","standard","I44";
;
CDS_LIB"standard"
BODY_TYPE"PLUMBING"
HDL_TAP"TRUE";
"B \NAC \NWC"15;
"S \NAC"
BN"13"101;
%"TAP"
"1","(-1100,1375)","0","standard","I45";
;
CDS_LIB"standard"
BODY_TYPE"PLUMBING"
HDL_TAP"TRUE";
"B \NAC \NWC"15;
"S \NAC"
BN"12"100;
%"TAP"
"1","(-1100,1575)","0","standard","I46";
;
CDS_LIB"standard"
BODY_TYPE"PLUMBING"
HDL_TAP"TRUE";
"B \NAC \NWC"15;
"S \NAC"
BN"16"104;
%"TAP"
"1","(-1100,1525)","0","standard","I47";
;
CDS_LIB"standard"
BODY_TYPE"PLUMBING"
HDL_TAP"TRUE";
"B \NAC \NWC"15;
"S \NAC"
BN"15"103;
%"TAP"
"1","(-1100,1725)","0","standard","I48";
;
CDS_LIB"standard"
BODY_TYPE"PLUMBING"
HDL_TAP"TRUE";
"B \NAC \NWC"15;
"S \NAC"
BN"19"78;
%"TAP"
"1","(-1100,1675)","0","standard","I49";
;
CDS_LIB"standard"
BODY_TYPE"PLUMBING"
HDL_TAP"TRUE";
"B \NAC \NWC"15;
"S \NAC"
BN"18"106;
%"TAP"
"1","(-1100,1625)","0","standard","I50";
;
CDS_LIB"standard"
BODY_TYPE"PLUMBING"
HDL_TAP"TRUE";
"B \NAC \NWC"15;
"S \NAC"
BN"17"105;
%"TAP"
"1","(-1100,1775)","0","standard","I51";
;
CDS_LIB"standard"
BODY_TYPE"PLUMBING"
HDL_TAP"TRUE";
"B \NAC \NWC"15;
"S \NAC"
BN"20"107;
%"TAP"
"1","(-1100,1825)","0","standard","I52";
;
CDS_LIB"standard"
BODY_TYPE"PLUMBING"
HDL_TAP"TRUE";
"B \NAC \NWC"15;
"S \NAC"
BN"21"108;
%"TAP"
"1","(-1100,1875)","0","standard","I53";
;
CDS_LIB"standard"
BODY_TYPE"PLUMBING"
HDL_TAP"TRUE";
"B \NAC \NWC"15;
"S \NAC"
BN"22"109;
%"TAP"
"1","(-1100,1975)","0","standard","I54";
;
CDS_LIB"standard"
BODY_TYPE"PLUMBING"
HDL_TAP"TRUE";
"B \NAC \NWC"15;
"S \NAC"
BN"24"77;
%"TAP"
"1","(-1100,1925)","0","standard","I55";
;
CDS_LIB"standard"
BODY_TYPE"PLUMBING"
HDL_TAP"TRUE";
"B \NAC \NWC"15;
"S \NAC"
BN"23"110;
%"TAP"
"1","(-2750,2075)","2","standard","I56";
;
CDS_LIB"standard"
BODY_TYPE"PLUMBING"
HDL_TAP"TRUE";
"B \NAC \NWC"12;
"S \NAC"
BN"6"154;
%"TAP"
"1","(-2750,2025)","2","standard","I57";
;
CDS_LIB"standard"
BODY_TYPE"PLUMBING"
HDL_TAP"TRUE";
"B \NAC \NWC"12;
"S \NAC"
BN"5"153;
%"TAP"
"1","(-2750,2225)","2","standard","I58";
;
CDS_LIB"standard"
BODY_TYPE"PLUMBING"
HDL_TAP"TRUE";
"B \NAC \NWC"11;
"S \NAC"
BN"0"155;
%"TAP"
"1","(-2750,2125)","2","standard","I59";
;
CDS_LIB"standard"
BODY_TYPE"PLUMBING"
HDL_TAP"TRUE";
"B \NAC \NWC"12;
"S \NAC"
BN"7"173;
%"TAP"
"1","(-2750,2275)","2","standard","I60";
;
CDS_LIB"standard"
BODY_TYPE"PLUMBING"
HDL_TAP"TRUE";
"B \NAC \NWC"11;
"S \NAC"
BN"1"174;
%"TAP"
"1","(-2750,2325)","2","standard","I61";
;
CDS_LIB"standard"
BODY_TYPE"PLUMBING"
HDL_TAP"TRUE";
"B \NAC \NWC"11;
"S \NAC"
BN"2"156;
%"TAP"
"1","(-2750,2375)","2","standard","I62";
;
CDS_LIB"standard"
BODY_TYPE"PLUMBING"
HDL_TAP"TRUE";
"B \NAC \NWC"11;
"S \NAC"
BN"3"157;
%"TAP"
"1","(-2750,2475)","2","standard","I63";
;
CDS_LIB"standard"
BODY_TYPE"PLUMBING"
HDL_TAP"TRUE";
"B \NAC \NWC"11;
"S \NAC"
BN"5"158;
%"TAP"
"1","(-2750,2425)","2","standard","I64";
;
CDS_LIB"standard"
BODY_TYPE"PLUMBING"
HDL_TAP"TRUE";
"B \NAC \NWC"11;
"S \NAC"
BN"4"175;
%"TAP"
"1","(-2750,2575)","2","standard","I65";
;
CDS_LIB"standard"
BODY_TYPE"PLUMBING"
HDL_TAP"TRUE";
"B \NAC \NWC"11;
"S \NAC"
BN"7"176;
%"TAP"
"1","(-2750,2525)","2","standard","I66";
;
CDS_LIB"standard"
BODY_TYPE"PLUMBING"
HDL_TAP"TRUE";
"B \NAC \NWC"11;
"S \NAC"
BN"6"159;
%"TAP"
"1","(-2750,3275)","2","standard","I67";
;
CDS_LIB"standard"
BODY_TYPE"PLUMBING"
HDL_TAP"TRUE";
"B \NAC \NWC"14;
"S \NAC"
BN"0"72;
%"TAP"
"1","(-2750,3325)","2","standard","I68";
;
CDS_LIB"standard"
BODY_TYPE"PLUMBING"
HDL_TAP"TRUE";
"B \NAC \NWC"14;
"S \NAC"
BN"1"170;
%"TAP"
"1","(-2750,3375)","2","standard","I69";
;
CDS_LIB"standard"
BODY_TYPE"PLUMBING"
HDL_TAP"TRUE";
"B \NAC \NWC"14;
"S \NAC"
BN"2"168;
%"TAP"
"1","(-2750,3425)","2","standard","I70";
;
CDS_LIB"standard"
BODY_TYPE"PLUMBING"
HDL_TAP"TRUE";
"B \NAC \NWC"14;
"S \NAC"
BN"3"166;
%"TAP"
"1","(-2750,3475)","2","standard","I71";
;
CDS_LIB"standard"
BODY_TYPE"PLUMBING"
HDL_TAP"TRUE";
"B \NAC \NWC"14;
"S \NAC"
BN"4"164;
%"TAP"
"1","(-2750,3525)","2","standard","I72";
;
CDS_LIB"standard"
BODY_TYPE"PLUMBING"
HDL_TAP"TRUE";
"B \NAC \NWC"14;
"S \NAC"
BN"5"162;
%"TAP"
"1","(-2750,3575)","2","standard","I73";
;
CDS_LIB"standard"
BODY_TYPE"PLUMBING"
HDL_TAP"TRUE";
"B \NAC \NWC"14;
"S \NAC"
BN"6"160;
%"TAP"
"1","(-2750,3725)","2","standard","I74";
;
CDS_LIB"standard"
BODY_TYPE"PLUMBING"
HDL_TAP"TRUE";
"B \NAC \NWC"13;
"S \NAC"
BN"1"171;
%"TAP"
"1","(-2750,3675)","2","standard","I75";
;
CDS_LIB"standard"
BODY_TYPE"PLUMBING"
HDL_TAP"TRUE";
"B \NAC \NWC"13;
"S \NAC"
BN"0"172;
%"TAP"
"1","(-2750,3775)","2","standard","I76";
;
CDS_LIB"standard"
BODY_TYPE"PLUMBING"
HDL_TAP"TRUE";
"B \NAC \NWC"13;
"S \NAC"
BN"2"169;
%"TAP"
"1","(-2750,3825)","2","standard","I77";
;
CDS_LIB"standard"
BODY_TYPE"PLUMBING"
HDL_TAP"TRUE";
"B \NAC \NWC"13;
"S \NAC"
BN"3"167;
%"TAP"
"1","(-2750,3875)","2","standard","I78";
;
CDS_LIB"standard"
BODY_TYPE"PLUMBING"
HDL_TAP"TRUE";
"B \NAC \NWC"13;
"S \NAC"
BN"4"165;
%"TAP"
"1","(-2750,3925)","2","standard","I79";
;
CDS_LIB"standard"
BODY_TYPE"PLUMBING"
HDL_TAP"TRUE";
"B \NAC \NWC"13;
"S \NAC"
BN"5"163;
%"TAP"
"1","(-2750,3975)","2","standard","I80";
;
CDS_LIB"standard"
BODY_TYPE"PLUMBING"
HDL_TAP"TRUE";
"B \NAC \NWC"13;
"S \NAC"
BN"6"161;
%"TAP"
"1","(-1100,2125)","0","standard","I81";
;
CDS_LIB"standard"
BODY_TYPE"PLUMBING"
HDL_TAP"TRUE";
"B \NAC \NWC"15;
"S \NAC"
BN"27"111;
%"TAP"
"1","(-1100,2075)","0","standard","I82";
;
CDS_LIB"standard"
BODY_TYPE"PLUMBING"
HDL_TAP"TRUE";
"B \NAC \NWC"15;
"S \NAC"
BN"26"75;
%"TAP"
"1","(-1100,2025)","0","standard","I83";
;
CDS_LIB"standard"
BODY_TYPE"PLUMBING"
HDL_TAP"TRUE";
"B \NAC \NWC"15;
"S \NAC"
BN"25"76;
%"TAP"
"1","(-1100,2225)","0","standard","I84";
;
CDS_LIB"standard"
BODY_TYPE"PLUMBING"
HDL_TAP"TRUE";
"B \NAC \NWC"15;
"S \NAC"
BN"29"82;
%"TAP"
"1","(-1100,2175)","0","standard","I85";
;
CDS_LIB"standard"
BODY_TYPE"PLUMBING"
HDL_TAP"TRUE";
"B \NAC \NWC"15;
"S \NAC"
BN"28"112;
%"TAP"
"1","(-1100,2325)","0","standard","I86";
;
CDS_LIB"standard"
BODY_TYPE"PLUMBING"
HDL_TAP"TRUE";
"B \NAC \NWC"15;
"S \NAC"
BN"31"113;
%"TAP"
"1","(-1100,2275)","0","standard","I87";
;
CDS_LIB"standard"
BODY_TYPE"PLUMBING"
HDL_TAP"TRUE";
"B \NAC \NWC"15;
"S \NAC"
BN"30"71;
%"TAP"
"1","(-1100,2425)","0","standard","I88";
;
CDS_LIB"standard"
BODY_TYPE"PLUMBING"
HDL_TAP"TRUE";
"B \NAC \NWC"10;
"S \NAC"
BN"0"114;
%"TAP"
"1","(-1100,2475)","0","standard","I89";
;
CDS_LIB"standard"
BODY_TYPE"PLUMBING"
HDL_TAP"TRUE";
"B \NAC \NWC"10;
"S \NAC"
BN"1"115;
%"TAP"
"1","(-1100,2625)","0","standard","I90";
;
CDS_LIB"standard"
BODY_TYPE"PLUMBING"
HDL_TAP"TRUE";
"B \NAC \NWC"10;
"S \NAC"
BN"4"118;
%"TAP"
"1","(-1100,2575)","0","standard","I91";
;
CDS_LIB"standard"
BODY_TYPE"PLUMBING"
HDL_TAP"TRUE";
"B \NAC \NWC"10;
"S \NAC"
BN"3"117;
%"TAP"
"1","(-1100,2525)","0","standard","I92";
;
CDS_LIB"standard"
BODY_TYPE"PLUMBING"
HDL_TAP"TRUE";
"B \NAC \NWC"10;
"S \NAC"
BN"2"116;
%"TAP"
"1","(-1100,2725)","0","standard","I93";
;
CDS_LIB"standard"
BODY_TYPE"PLUMBING"
HDL_TAP"TRUE";
"B \NAC \NWC"10;
"S \NAC"
BN"6"81;
%"TAP"
"1","(-1100,2675)","0","standard","I94";
;
CDS_LIB"standard"
BODY_TYPE"PLUMBING"
HDL_TAP"TRUE";
"B \NAC \NWC"10;
"S \NAC"
BN"5"119;
%"TAP"
"1","(-1100,2875)","0","standard","I95";
;
CDS_LIB"standard"
BODY_TYPE"PLUMBING"
HDL_TAP"TRUE";
"B \NAC \NWC"10;
"S \NAC"
BN"9"122;
%"TAP"
"1","(-1100,2775)","0","standard","I96";
;
CDS_LIB"standard"
BODY_TYPE"PLUMBING"
HDL_TAP"TRUE";
"B \NAC \NWC"10;
"S \NAC"
BN"7"120;
%"TAP"
"1","(-1100,2825)","0","standard","I97";
;
CDS_LIB"standard"
BODY_TYPE"PLUMBING"
HDL_TAP"TRUE";
"B \NAC \NWC"10;
"S \NAC"
BN"8"121;
%"TAP"
"1","(-1100,2925)","0","standard","I98";
;
CDS_LIB"standard"
BODY_TYPE"PLUMBING"
HDL_TAP"TRUE";
"B \NAC \NWC"10;
"S \NAC"
BN"10"123;
%"TAP"
"1","(-1100,2975)","0","standard","I99";
;
CDS_LIB"standard"
BODY_TYPE"PLUMBING"
HDL_TAP"TRUE";
"B \NAC \NWC"10;
"S \NAC"
BN"11"124;
END.
